(kicad_pcb
	(version 20260206)
	(generator "pcbnew")
	(generator_version "10.0")
	(general
		(thickness 1.6)
		(legacy_teardrops no)
	)
	(paper "A4")
	(title_block
		(title "Bryce Canyon_R.DPB_16317-1_OCP.brd")
		(comment 1 "Bryce Canyon / footprints 266-273 of 2099")
	)
	(layers
		(0 "F.Cu" signal "TOP")
		(4 "In1.Cu" signal "L2GND")
		(6 "In2.Cu" signal "L3")
		(8 "In3.Cu" signal "L4VCC")
		(10 "In4.Cu" signal "L5VCC")
		(12 "In5.Cu" signal "L6")
		(14 "In6.Cu" signal "L7GND")
		(2 "B.Cu" signal "BOTTOM")
		(9 "F.Adhes" user "F.Adhesive")
		(11 "B.Adhes" user "B.Adhesive")
		(13 "F.Paste" user "Package Geometry/Pastemask Top")
		(15 "B.Paste" user "Package Geometry/Pastemask Bottom")
		(5 "F.SilkS" user "Ref Des/Silkscreen Top")
		(7 "B.SilkS" user "Ref Des/Silkscreen Bottom")
		(1 "F.Mask" user "Board Geometry/Soldermask Top")
		(3 "B.Mask" user "Board Geometry/Soldermask Bottom")
		(17 "Dwgs.User" user "User.Drawings")
		(19 "Cmts.User" user "User.Comments")
		(21 "Eco1.User" user "User.Eco1")
		(23 "Eco2.User" user "User.Eco2")
		(25 "Edge.Cuts" user "Board Geometry/Outline")
		(27 "Margin" user)
		(31 "F.CrtYd" user "Package Geometry/Place Bound Top")
		(29 "B.CrtYd" user "Package Geometry/Place Bound Bottom")
		(35 "F.Fab" user "Ref Des/Assembly Top")
		(33 "B.Fab" user "Ref Des/Assembly Bottom")
	)
	(footprint ""
		(layer "F.Cu")
		(at 64.013334 -15.219426 90)
		(property "Reference" "C353"
			(at 0 0 90)
			(layer "F.SilkS")
			(hide yes)
			(effects
				(font
					(size 1.27 1.27)
				)
			)
		)
		(property "Value" "SCD01U16V1KX-GP"
			(at -2.8321 -1.7399 90)
			(unlocked yes)
			(layer "F.Fab")
			(hide yes)
			(effects
				(font
					(size 1.016 1.016)
					(thickness 0.1524)
				)
			)
		)
		(property "Device Type" "C0201H13"
			(at -2.8321 -3.2639 90)
			(unlocked yes)
			(layer "F.Fab")
			(hide yes)
			(effects
				(font
					(size 1.016 1.016)
					(thickness 0.1524)
				)
			)
		)
		(duplicate_pad_numbers_are_jumpers no)
		(fp_rect
			(start -0.2794 0.6477)
			(end 0.2794 -0.6477)
			(stroke
				(width 0)
				(type default)
			)
			(fill no)
			(layer "F.CrtYd")
		)
		(fp_rect
			(start -0.2794 0.6477)
			(end 0.2794 -0.6477)
			(stroke
				(width 0)
				(type default)
			)
			(fill no)
			(layer "F.Fab")
		)
		(pad "1" smd custom
			(at 0 -0.2794 90)
			(size 0.0762 0.0762)
			(layers "F.Cu" "F.Mask" "F.Paste")
			(net "SAS_HDD_RX_N25")
			(options
				(clearance outline)
				(anchor circle)
			)
			(primitives
				(gr_poly
					(pts
						(arc
							(start 0.1524 -0.127)
							(mid 0.137521 -0.162921)
							(end 0.1016 -0.1778)
						)
						(arc
							(start -0.1016 -0.1778)
							(mid -0.137521 -0.162921)
							(end -0.1524 -0.127)
						)
						(arc
							(start -0.1524 0.127)
							(mid -0.137521 0.162921)
							(end -0.1016 0.1778)
						)
						(arc
							(start 0.1016 0.1778)
							(mid 0.137521 0.162921)
							(end 0.1524 0.127)
						)
					)
					(width 0)
					(fill yes)
				)
			)
		)
		(pad "2" smd custom
			(at 0 0.2794 90)
			(size 0.0762 0.0762)
			(layers "F.Cu" "F.Mask" "F.Paste")
			(net "PHY_SCC_B_TO_DRV_B_25_DN")
			(options
				(clearance outline)
				(anchor circle)
			)
			(primitives
				(gr_poly
					(pts
						(arc
							(start 0.1524 -0.127)
							(mid 0.137521 -0.162921)
							(end 0.1016 -0.1778)
						)
						(arc
							(start -0.1016 -0.1778)
							(mid -0.137521 -0.162921)
							(end -0.1524 -0.127)
						)
						(arc
							(start -0.1524 0.127)
							(mid -0.137521 0.162921)
							(end -0.1016 0.1778)
						)
						(arc
							(start 0.1016 0.1778)
							(mid 0.137521 0.162921)
							(end 0.1524 0.127)
						)
					)
					(width 0)
					(fill yes)
				)
			)
		)
	)
	(footprint ""
		(layer "F.Cu")
		(at 394.589 -262.001 -90)
		(property "Reference" "R286"
			(at 0 0 270)
			(layer "F.SilkS")
			(hide yes)
			(effects
				(font
					(size 1.27 1.27)
				)
			)
		)
		(property "Value" "2R6F-GP"
			(at -0.0508 -4.8514 270)
			(unlocked yes)
			(layer "F.Fab")
			(hide yes)
			(effects
				(font
					(size 1.016 1.016)
					(thickness 0.1524)
				)
			)
		)
		(property "Device Type" "R1206H26"
			(at 0 -6.3754 270)
			(unlocked yes)
			(layer "F.Fab")
			(hide yes)
			(effects
				(font
					(size 1.016 1.016)
					(thickness 0.1524)
				)
			)
		)
		(duplicate_pad_numbers_are_jumpers no)
		(fp_line
			(start -1.016 2.2352)
			(end -1.016 -2.2352)
			(stroke
				(width 0.1524)
				(type default)
			)
			(layer "F.SilkS")
		)
		(fp_line
			(start 1.016 2.2352)
			(end -1.016 2.2352)
			(stroke
				(width 0.1524)
				(type default)
			)
			(layer "F.SilkS")
		)
		(fp_line
			(start -1.016 -2.2352)
			(end 1.016 -2.2352)
			(stroke
				(width 0.1524)
				(type default)
			)
			(layer "F.SilkS")
		)
		(fp_line
			(start 1.016 -2.2352)
			(end 1.016 2.2352)
			(stroke
				(width 0.1524)
				(type default)
			)
			(layer "F.SilkS")
		)
		(fp_rect
			(start -1.0922 2.3114)
			(end 1.0922 -2.3114)
			(stroke
				(width 0)
				(type default)
			)
			(fill no)
			(layer "F.CrtYd")
		)
		(fp_poly
			(pts
				(xy -1.0922 -2.3114) (xy 1.0922 -2.3114) (xy 1.0922 2.3114) (xy -1.0922 2.3114)
			)
			(stroke
				(width 0)
				(type default)
			)
			(fill no)
			(layer "F.Fab")
		)
		(pad "1" smd rect
			(at 0 -1.397 270)
			(size 1.651 1.27)
			(layers "F.Cu" "F.Mask" "F.Paste")
			(net "P5V_HDD8")
		)
		(pad "2" smd rect
			(at 0 1.397 270)
			(size 1.651 1.27)
			(layers "F.Cu" "F.Mask" "F.Paste")
			(net "5V_PRE_8")
		)
	)
	(footprint ""
		(layer "F.Cu")
		(at 95.377 -31.6484)
		(property "Reference" "C375"
			(at 0 0 0)
			(layer "F.SilkS")
			(hide yes)
			(effects
				(font
					(size 1.27 1.27)
				)
			)
		)
		(property "Value" "SCD01U50V2KX-1GP"
			(at 1.1811 -2.7051 0)
			(unlocked yes)
			(layer "F.Fab")
			(hide yes)
			(effects
				(font
					(size 1.016 1.016)
					(thickness 0.1524)
				)
			)
		)
		(property "Device Type" "C402H22"
			(at 1.1811 -4.2291 0)
			(unlocked yes)
			(layer "F.Fab")
			(hide yes)
			(effects
				(font
					(size 1.016 1.016)
					(thickness 0.1524)
				)
			)
		)
		(duplicate_pad_numbers_are_jumpers no)
		(fp_rect
			(start -0.4318 0.9525)
			(end 0.4318 -0.9525)
			(stroke
				(width 0)
				(type default)
			)
			(fill no)
			(layer "F.CrtYd")
		)
		(fp_rect
			(start -0.4318 0.9525)
			(end 0.4318 -0.9525)
			(stroke
				(width 0)
				(type default)
			)
			(fill no)
			(layer "F.Fab")
		)
		(pad "1" smd custom
			(at 0 -0.4445)
			(size 0.1524 0.1524)
			(layers "F.Cu" "F.Mask" "F.Paste")
			(net "HDD_PRSNT_26")
			(options
				(clearance outline)
				(anchor circle)
			)
			(primitives
				(gr_poly
					(pts
						(arc
							(start 0.3048 -0.2032)
							(mid 0.275042 -0.275042)
							(end 0.2032 -0.3048)
						)
						(arc
							(start -0.2032 -0.3048)
							(mid -0.275042 -0.275042)
							(end -0.3048 -0.2032)
						)
						(arc
							(start -0.3048 0.2032)
							(mid -0.275042 0.275042)
							(end -0.2032 0.3048)
						)
						(arc
							(start 0.2032 0.3048)
							(mid 0.275042 0.275042)
							(end 0.3048 0.2032)
						)
					)
					(width 0)
					(fill yes)
				)
			)
		)
		(pad "2" smd custom
			(at 0 0.4445)
			(size 0.1524 0.1524)
			(layers "F.Cu" "F.Mask" "F.Paste")
			(net "GND")
			(options
				(clearance outline)
				(anchor circle)
			)
			(primitives
				(gr_poly
					(pts
						(arc
							(start 0.3048 -0.2032)
							(mid 0.275042 -0.275042)
							(end 0.2032 -0.3048)
						)
						(arc
							(start -0.2032 -0.3048)
							(mid -0.275042 -0.275042)
							(end -0.3048 -0.2032)
						)
						(arc
							(start -0.3048 0.2032)
							(mid -0.275042 0.275042)
							(end -0.2032 0.3048)
						)
						(arc
							(start 0.2032 0.3048)
							(mid 0.275042 0.275042)
							(end 0.3048 0.2032)
						)
					)
					(width 0)
					(fill yes)
				)
			)
		)
	)
	(footprint ""
		(layer "F.Cu")
		(at 331.47 -147.066 -90)
		(property "Reference" "R483"
			(at 0 0 270)
			(layer "F.SilkS")
			(hide yes)
			(effects
				(font
					(size 1.27 1.27)
				)
			)
		)
		(property "Value" "2R6F-GP"
			(at -0.0508 -4.8514 270)
			(unlocked yes)
			(layer "F.Fab")
			(hide yes)
			(effects
				(font
					(size 1.016 1.016)
					(thickness 0.1524)
				)
			)
		)
		(property "Device Type" "R1206H26"
			(at 0 -6.3754 270)
			(unlocked yes)
			(layer "F.Fab")
			(hide yes)
			(effects
				(font
					(size 1.016 1.016)
					(thickness 0.1524)
				)
			)
		)
		(duplicate_pad_numbers_are_jumpers no)
		(fp_line
			(start -1.016 2.2352)
			(end -1.016 -2.2352)
			(stroke
				(width 0.1524)
				(type default)
			)
			(layer "F.SilkS")
		)
		(fp_line
			(start 1.016 2.2352)
			(end -1.016 2.2352)
			(stroke
				(width 0.1524)
				(type default)
			)
			(layer "F.SilkS")
		)
		(fp_line
			(start -1.016 -2.2352)
			(end 1.016 -2.2352)
			(stroke
				(width 0.1524)
				(type default)
			)
			(layer "F.SilkS")
		)
		(fp_line
			(start 1.016 -2.2352)
			(end 1.016 2.2352)
			(stroke
				(width 0.1524)
				(type default)
			)
			(layer "F.SilkS")
		)
		(fp_rect
			(start -1.0922 2.3114)
			(end 1.0922 -2.3114)
			(stroke
				(width 0)
				(type default)
			)
			(fill no)
			(layer "F.CrtYd")
		)
		(fp_poly
			(pts
				(xy -1.0922 -2.3114) (xy 1.0922 -2.3114) (xy 1.0922 2.3114) (xy -1.0922 2.3114)
			)
			(stroke
				(width 0)
				(type default)
			)
			(fill no)
			(layer "F.Fab")
		)
		(pad "1" smd rect
			(at 0 -1.397 270)
			(size 1.651 1.27)
			(layers "F.Cu" "F.Mask" "F.Paste")
			(net "P5V_HDD18")
		)
		(pad "2" smd rect
			(at 0 1.397 270)
			(size 1.651 1.27)
			(layers "F.Cu" "F.Mask" "F.Paste")
			(net "5V_PRE_18")
		)
	)
	(footprint ""
		(layer "F.Cu")
		(at 318.2112 -147.8534 180)
		(property "Reference" "R488"
			(at 0 0 180)
			(layer "F.SilkS")
			(hide yes)
			(effects
				(font
					(size 1.27 1.27)
				)
			)
		)
		(property "Value" "220R3F-1-GP"
			(at -0.0254 -2.5146 180)
			(unlocked yes)
			(layer "F.Fab")
			(hide yes)
			(effects
				(font
					(size 1.016 1.016)
					(thickness 0.1524)
				)
			)
		)
		(property "Device Type" "R603H22"
			(at -0.0254 -4.0386 180)
			(unlocked yes)
			(layer "F.Fab")
			(hide yes)
			(effects
				(font
					(size 1.016 1.016)
					(thickness 0.1524)
				)
			)
		)
		(duplicate_pad_numbers_are_jumpers no)
		(fp_line
			(start 0.2032 0)
			(end 0.4826 0)
			(stroke
				(width 0.2032)
				(type default)
			)
			(layer "F.SilkS")
		)
		(fp_line
			(start -0.4826 0)
			(end -0.2032 0)
			(stroke
				(width 0.2032)
				(type default)
			)
			(layer "F.SilkS")
		)
		(fp_rect
			(start -0.5842 1.3335)
			(end 0.5842 -1.3335)
			(stroke
				(width 0)
				(type default)
			)
			(fill no)
			(layer "F.CrtYd")
		)
		(fp_rect
			(start -0.5842 1.3335)
			(end 0.5842 -1.3335)
			(stroke
				(width 0)
				(type default)
			)
			(fill no)
			(layer "F.Fab")
		)
		(pad "1" smd custom
			(at 0 -0.762 180)
			(size 0.2159 0.2159)
			(layers "F.Cu" "F.Mask" "F.Paste")
			(net "HDD_PRSNT_18")
			(options
				(clearance outline)
				(anchor circle)
			)
			(primitives
				(gr_poly
					(pts
						(arc
							(start -0.3302 -0.4318)
							(mid -0.402042 -0.402042)
							(end -0.4318 -0.3302)
						)
						(arc
							(start -0.4318 0.3302)
							(mid -0.402042 0.402042)
							(end -0.3302 0.4318)
						)
						(arc
							(start 0.3302 0.4318)
							(mid 0.402042 0.402042)
							(end 0.4318 0.3302)
						)
						(arc
							(start 0.4318 -0.3302)
							(mid 0.402042 -0.402042)
							(end 0.3302 -0.4318)
						)
					)
					(width 0)
					(fill yes)
				)
			)
		)
		(pad "2" smd custom
			(at 0 0.762 180)
			(size 0.2159 0.2159)
			(layers "F.Cu" "F.Mask" "F.Paste")
			(net "DRIVE_B_18_INS")
			(options
				(clearance outline)
				(anchor circle)
			)
			(primitives
				(gr_poly
					(pts
						(arc
							(start -0.3302 -0.4318)
							(mid -0.402042 -0.402042)
							(end -0.4318 -0.3302)
						)
						(arc
							(start -0.4318 0.3302)
							(mid -0.402042 0.402042)
							(end -0.3302 0.4318)
						)
						(arc
							(start 0.3302 0.4318)
							(mid 0.402042 0.402042)
							(end 0.4318 0.3302)
						)
						(arc
							(start 0.4318 -0.3302)
							(mid 0.402042 -0.402042)
							(end 0.3302 -0.4318)
						)
					)
					(width 0)
					(fill yes)
				)
			)
		)
	)
	(footprint ""
		(layer "F.Cu")
		(at 181.6862 -272.288)
		(property "Reference" "C100"
			(at 0 0 0)
			(layer "F.SilkS")
			(hide yes)
			(effects
				(font
					(size 1.27 1.27)
				)
			)
		)
		(property "Value" "SC4D7U25V5KX-1-GP"
			(at -0.0762 -6.1214 0)
			(unlocked yes)
			(layer "F.Fab")
			(hide yes)
			(effects
				(font
					(size 1.016 1.016)
					(thickness 0.1524)
				)
			)
		)
		(property "Device Type" "C805H58"
			(at -0.0762 -8.1534 0)
			(unlocked yes)
			(layer "F.Fab")
			(hide yes)
			(effects
				(font
					(size 1.016 1.016)
					(thickness 0.1524)
				)
			)
		)
		(duplicate_pad_numbers_are_jumpers no)
		(fp_line
			(start 0.635 0)
			(end -0.635 0)
			(stroke
				(width 0.508)
				(type default)
			)
			(layer "F.SilkS")
		)
		(fp_rect
			(start -0.9652 1.778)
			(end 0.9652 -1.778)
			(stroke
				(width 0)
				(type default)
			)
			(fill no)
			(layer "F.CrtYd")
		)
		(fp_poly
			(pts
				(xy -0.9652 -1.778) (xy 0.9652 -1.778) (xy 0.9652 1.778) (xy -0.9652 1.778)
			)
			(stroke
				(width 0)
				(type default)
			)
			(fill no)
			(layer "F.Fab")
		)
		(pad "1" smd rect
			(at 0 -0.9652)
			(size 1.397 1.143)
			(layers "F.Cu" "F.Mask" "F.Paste")
			(net "P12V_HDD5")
		)
		(pad "2" smd rect
			(at 0 0.9652)
			(size 1.397 1.143)
			(layers "F.Cu" "F.Mask" "F.Paste")
			(net "GND")
		)
	)
	(footprint ""
		(layer "F.Cu")
		(at 77.978 -131.572 90)
		(property "Reference" "R406"
			(at 0 0 90)
			(layer "F.SilkS")
			(hide yes)
			(effects
				(font
					(size 1.27 1.27)
				)
			)
		)
		(property "Value" "4K7R2J-2-GP"
			(at 0.064008 -3.993896 90)
			(unlocked yes)
			(layer "F.Fab")
			(hide yes)
			(effects
				(font
					(size 1.016 1.016)
					(thickness 0.1524)
				)
			)
		)
		(property "Device Type" "R402H16"
			(at 0.064008 -5.517896 90)
			(unlocked yes)
			(layer "F.Fab")
			(hide yes)
			(effects
				(font
					(size 1.016 1.016)
					(thickness 0.1524)
				)
			)
		)
		(duplicate_pad_numbers_are_jumpers no)
		(fp_line
			(start 0.508 -0.9398)
			(end -0.508 -0.9398)
			(stroke
				(width 0.1524)
				(type default)
			)
			(layer "F.SilkS")
		)
		(fp_line
			(start -0.508 -0.9398)
			(end -0.508 0.9398)
			(stroke
				(width 0.1524)
				(type default)
			)
			(layer "F.SilkS")
		)
		(fp_rect
			(start -0.508 0.9398)
			(end 0.508 -0.9398)
			(stroke
				(width 0)
				(type default)
			)
			(fill no)
			(layer "F.CrtYd")
		)
		(fp_rect
			(start -0.508 0.9398)
			(end 0.508 -0.9398)
			(stroke
				(width 0)
				(type default)
			)
			(fill no)
			(layer "F.Fab")
		)
		(pad "1" smd custom
			(at 0 -0.4445 90)
			(size 0.1397 0.1397)
			(layers "F.Cu" "F.Mask" "F.Paste")
			(net "P12V_B")
			(options
				(clearance outline)
				(anchor circle)
			)
			(primitives
				(gr_poly
					(pts
						(arc
							(start -0.1778 -0.2794)
							(mid -0.249642 -0.249642)
							(end -0.2794 -0.1778)
						)
						(arc
							(start -0.2794 0.1778)
							(mid -0.249642 0.249642)
							(end -0.1778 0.2794)
						)
						(arc
							(start 0.1778 0.2794)
							(mid 0.249642 0.249642)
							(end 0.2794 0.1778)
						)
						(arc
							(start 0.2794 -0.1778)
							(mid 0.249642 -0.249642)
							(end 0.1778 -0.2794)
						)
					)
					(width 0)
					(fill yes)
				)
			)
		)
		(pad "2" smd custom
			(at 0 0.4445 90)
			(size 0.1397 0.1397)
			(layers "F.Cu" "F.Mask" "F.Paste")
			(net "SW_HDD_R14")
			(options
				(clearance outline)
				(anchor circle)
			)
			(primitives
				(gr_poly
					(pts
						(arc
							(start -0.1778 -0.2794)
							(mid -0.249642 -0.249642)
							(end -0.2794 -0.1778)
						)
						(arc
							(start -0.2794 0.1778)
							(mid -0.249642 0.249642)
							(end -0.1778 0.2794)
						)
						(arc
							(start 0.1778 0.2794)
							(mid 0.249642 0.249642)
							(end 0.2794 0.1778)
						)
						(arc
							(start 0.2794 -0.1778)
							(mid 0.249642 -0.249642)
							(end 0.1778 -0.2794)
						)
					)
					(width 0)
					(fill yes)
				)
			)
		)
	)
	(footprint ""
		(layer "F.Cu")
		(at 314.623196 -372.237 -90)
		(property "Reference" "R972"
			(at 0 0 270)
			(layer "F.SilkS")
			(hide yes)
			(effects
				(font
					(size 1.27 1.27)
				)
			)
		)
		(property "Value" "1KR5F-1-GP"
			(at 0 -8.9535 270)
			(unlocked yes)
			(layer "F.Fab")
			(hide yes)
			(effects
				(font
					(size 1.27 1.016)
					(thickness 0.1524)
				)
			)
		)
		(property "Device Type" "R805H24"
			(at 0 -10.6299 270)
			(unlocked yes)
			(layer "F.Fab")
			(hide yes)
			(effects
				(font
					(size 1.27 1.016)
					(thickness 0.1524)
				)
			)
		)
		(duplicate_pad_numbers_are_jumpers no)
		(fp_line
			(start -0.889 1.7018)
			(end 0.889 1.7018)
			(stroke
				(width 0.1524)
				(type default)
			)
			(layer "F.SilkS")
		)
		(fp_line
			(start 0.889 1.7018)
			(end 0.889 -0.508)
			(stroke
				(width 0.1524)
				(type default)
			)
			(layer "F.SilkS")
		)
		(fp_line
			(start -0.889 0.0762)
			(end -0.889 1.7018)
			(stroke
				(width 0.1524)
				(type default)
			)
			(layer "F.SilkS")
		)
		(fp_line
			(start -0.889 -1.7018)
			(end -0.889 0.2794)
			(stroke
				(width 0.1524)
				(type default)
			)
			(layer "F.SilkS")
		)
		(fp_line
			(start 0.889 -1.7018)
			(end 0.889 -0.381)
			(stroke
				(width 0.1524)
				(type default)
			)
			(layer "F.SilkS")
		)
		(fp_line
			(start 0.889 -1.7018)
			(end -0.889 -1.7018)
			(stroke
				(width 0.1524)
				(type default)
			)
			(layer "F.SilkS")
		)
		(fp_poly
			(pts
				(xy 0.9652 -1.778) (xy 0.9652 1.778) (xy -0.9652 1.778) (xy -0.9652 -1.778)
			)
			(stroke
				(width 0)
				(type default)
			)
			(fill no)
			(layer "F.CrtYd")
		)
		(fp_rect
			(start -0.9652 1.778)
			(end 0.9652 -1.778)
			(stroke
				(width 0)
				(type default)
			)
			(fill no)
			(layer "F.Fab")
		)
		(pad "1" smd rect
			(at 0 -0.9652 270)
			(size 1.397 1.143)
			(layers "F.Cu" "F.Mask" "F.Paste")
			(net "FAN_YELLOW_2")
		)
		(pad "2" smd rect
			(at 0 0.9652 270)
			(size 1.397 1.143)
			(layers "F.Cu" "F.Mask" "F.Paste")
			(net "FAN_LED_YELLOW_2")
		)
	)
)
